# T6G (Grand Teton) — schematic netlist excerpt (pin names and nets, part order shuffled) for the footprints in the layout excerpt that follows; sources: Cadence DE-HDL packaged netlist, KiCad conversion of 04192023_DAF0TMB3IC0_F0TG_MB_C_brd_V02_OCP.brd

R6026  Q_RES  0 5% CHIP  pkg 0402LF  page 150 : A = SGPIO_SCM_INTR_N ; B = SGPIO_SCM_INTR_R1_N
C7038  Q_CAP  47UF 4V 20% X6S  pkg C0805  page 345 : A = P0V9_CPU1_RT_2D ; B = GND
R246  Q_RES  0 5% CHIP  pkg 0402LF  page 82 : A = IRQ_TPM_SPI_R_N ; B = IRQ_TPM_SPI_R1_N

(kicad_pcb
	(version 20260206)
	(generator "pcbnew")
	(generator_version "10.0")
	(general
		(thickness 1.6)
		(legacy_teardrops no)
	)
	(paper "A4")
	(title_block
		(title "04192023_DAF0TMB3IC0_F0TG_MB_C_brd_V02_OCP.brd")
		(comment 1 "Grand Teton / footprints 4613-4615 of 8354")
	)
	(layers
		(0 "F.Cu" signal "TOP")
		(4 "In1.Cu" signal "GND")
		(6 "In2.Cu" signal "IN1")
		(8 "In3.Cu" signal "GND1")
		(10 "In4.Cu" signal "IN2")
		(12 "In5.Cu" signal "GND2")
		(14 "In6.Cu" signal "IN3")
		(16 "In7.Cu" signal "GND3")
		(18 "In8.Cu" signal "VCC")
		(20 "In9.Cu" signal "VCC1")
		(22 "In10.Cu" signal "GND4")
		(24 "In11.Cu" signal "IN4")
		(26 "In12.Cu" signal "GND5")
		(28 "In13.Cu" signal "IN5")
		(30 "In14.Cu" signal "GND6")
		(32 "In15.Cu" signal "IN6")
		(34 "In16.Cu" signal "GND7")
		(2 "B.Cu" signal "BOTTOM")
		(9 "F.Adhes" user "F.Adhesive")
		(11 "B.Adhes" user "B.Adhesive")
		(13 "F.Paste" user "Package Geometry/Pastemask Top")
		(15 "B.Paste" user "Package Geometry/Pastemask Bottom")
		(5 "F.SilkS" user "Ref Des/Silkscreen Top")
		(7 "B.SilkS" user "Ref Des/Silkscreen Bottom")
		(1 "F.Mask" user "Board Geometry/Soldermask Top")
		(3 "B.Mask" user "Board Geometry/Soldermask Bottom")
		(17 "Dwgs.User" user "User.Drawings")
		(19 "Cmts.User" user "User.Comments")
		(21 "Eco1.User" user "User.Eco1")
		(23 "Eco2.User" user "User.Eco2")
		(25 "Edge.Cuts" user "Board Geometry/Outline")
		(27 "Margin" user)
		(31 "F.CrtYd" user "Package Geometry/Place Bound Top")
		(29 "B.CrtYd" user "Package Geometry/Place Bound Bottom")
		(35 "F.Fab" user "Ref Des/Assembly Top")
		(33 "B.Fab" user "Ref Des/Assembly Bottom")
	)
	(footprint ""
		(layer "F.Cu")
		(at 149.987254 -23.284942 -90)
		(property "Reference" "R6026"
			(at 0 0 270)
			(layer "F.SilkS")
			(hide yes)
			(effects
				(font
					(size 1.27 1.27)
				)
			)
		)
		(property "Value" ""
			(at 0 0 270)
			(layer "F.Fab")
			(effects
				(font
					(size 1.27 1.27)
				)
			)
		)
		(duplicate_pad_numbers_are_jumpers no)
		(fp_line
			(start -0.7874 0.4064)
			(end -0.7874 -0.4064)
			(stroke
				(width 0.1524)
				(type default)
			)
			(layer "F.SilkS")
		)
		(fp_line
			(start 0.7874 0.4064)
			(end -0.7874 0.4064)
			(stroke
				(width 0.1524)
				(type default)
			)
			(layer "F.SilkS")
		)
		(fp_line
			(start -0.7874 -0.4064)
			(end 0.7874 -0.4064)
			(stroke
				(width 0.1524)
				(type default)
			)
			(layer "F.SilkS")
		)
		(fp_line
			(start 0.7874 -0.4064)
			(end 0.7874 0.4064)
			(stroke
				(width 0.1524)
				(type default)
			)
			(layer "F.SilkS")
		)
		(fp_line
			(start -0.67945 0.3048)
			(end -0.67945 -0.305054)
			(stroke
				(width 0.1)
				(type default)
			)
			(layer "F.Fab")
		)
		(fp_line
			(start -0.12065 0.3048)
			(end -0.67945 0.3048)
			(stroke
				(width 0.1)
				(type default)
			)
			(layer "F.Fab")
		)
		(fp_line
			(start 0.120396 0.3048)
			(end 0.120396 0.2794)
			(stroke
				(width 0.1)
				(type default)
			)
			(layer "F.Fab")
		)
		(fp_line
			(start 0.67945 0.3048)
			(end 0.120396 0.3048)
			(stroke
				(width 0.1)
				(type default)
			)
			(layer "F.Fab")
		)
		(fp_line
			(start -0.12065 0.2794)
			(end -0.12065 0.3048)
			(stroke
				(width 0.1)
				(type default)
			)
			(layer "F.Fab")
		)
		(fp_line
			(start 0.120396 0.2794)
			(end -0.12065 0.2794)
			(stroke
				(width 0.1)
				(type default)
			)
			(layer "F.Fab")
		)
		(fp_line
			(start -0.12065 -0.2794)
			(end 0.12065 -0.2794)
			(stroke
				(width 0.1)
				(type default)
			)
			(layer "F.Fab")
		)
		(fp_line
			(start 0.12065 -0.2794)
			(end 0.12065 -0.3048)
			(stroke
				(width 0.1)
				(type default)
			)
			(layer "F.Fab")
		)
		(fp_line
			(start 0.12065 -0.3048)
			(end 0.67945 -0.3048)
			(stroke
				(width 0.1)
				(type default)
			)
			(layer "F.Fab")
		)
		(fp_line
			(start 0.67945 -0.3048)
			(end 0.67945 0.3048)
			(stroke
				(width 0.1)
				(type default)
			)
			(layer "F.Fab")
		)
		(fp_line
			(start -0.67945 -0.305054)
			(end -0.12065 -0.305054)
			(stroke
				(width 0.1)
				(type default)
			)
			(layer "F.Fab")
		)
		(fp_line
			(start -0.12065 -0.305054)
			(end -0.12065 -0.2794)
			(stroke
				(width 0.1)
				(type default)
			)
			(layer "F.Fab")
		)
		(pad "1" smd circle
			(at -0.40005 0 270)
			(size 0 0)
			(layers "F.Cu" "F.Mask" "F.Paste")
			(net "SGPIO_SCM_INTR_N")
		)
		(pad "2" smd circle
			(at 0.40005 0 270)
			(size 0 0)
			(layers "F.Cu" "F.Mask" "F.Paste")
			(net "SGPIO_SCM_INTR_R1_N")
		)
	)
	(footprint ""
		(layer "F.Cu")
		(at 180.9242 -96.103948 90)
		(property "Reference" "R246"
			(at 0 0 90)
			(layer "F.SilkS")
			(hide yes)
			(effects
				(font
					(size 1.27 1.27)
				)
			)
		)
		(property "Value" ""
			(at 0 0 90)
			(layer "F.Fab")
			(effects
				(font
					(size 1.27 1.27)
				)
			)
		)
		(duplicate_pad_numbers_are_jumpers no)
		(fp_line
			(start 0.7874 -0.4064)
			(end 0.7874 0.4064)
			(stroke
				(width 0.1524)
				(type default)
			)
			(layer "F.SilkS")
		)
		(fp_line
			(start -0.7874 -0.4064)
			(end 0.7874 -0.4064)
			(stroke
				(width 0.1524)
				(type default)
			)
			(layer "F.SilkS")
		)
		(fp_line
			(start 0.7874 0.4064)
			(end -0.7874 0.4064)
			(stroke
				(width 0.1524)
				(type default)
			)
			(layer "F.SilkS")
		)
		(fp_line
			(start -0.7874 0.4064)
			(end -0.7874 -0.4064)
			(stroke
				(width 0.1524)
				(type default)
			)
			(layer "F.SilkS")
		)
		(fp_line
			(start -0.12065 -0.305054)
			(end -0.12065 -0.2794)
			(stroke
				(width 0.1)
				(type default)
			)
			(layer "F.Fab")
		)
		(fp_line
			(start -0.67945 -0.305054)
			(end -0.12065 -0.305054)
			(stroke
				(width 0.1)
				(type default)
			)
			(layer "F.Fab")
		)
		(fp_line
			(start 0.67945 -0.3048)
			(end 0.67945 0.3048)
			(stroke
				(width 0.1)
				(type default)
			)
			(layer "F.Fab")
		)
		(fp_line
			(start 0.12065 -0.3048)
			(end 0.67945 -0.3048)
			(stroke
				(width 0.1)
				(type default)
			)
			(layer "F.Fab")
		)
		(fp_line
			(start 0.12065 -0.2794)
			(end 0.12065 -0.3048)
			(stroke
				(width 0.1)
				(type default)
			)
			(layer "F.Fab")
		)
		(fp_line
			(start -0.12065 -0.2794)
			(end 0.12065 -0.2794)
			(stroke
				(width 0.1)
				(type default)
			)
			(layer "F.Fab")
		)
		(fp_line
			(start 0.120396 0.2794)
			(end -0.12065 0.2794)
			(stroke
				(width 0.1)
				(type default)
			)
			(layer "F.Fab")
		)
		(fp_line
			(start -0.12065 0.2794)
			(end -0.12065 0.3048)
			(stroke
				(width 0.1)
				(type default)
			)
			(layer "F.Fab")
		)
		(fp_line
			(start 0.67945 0.3048)
			(end 0.120396 0.3048)
			(stroke
				(width 0.1)
				(type default)
			)
			(layer "F.Fab")
		)
		(fp_line
			(start 0.120396 0.3048)
			(end 0.120396 0.2794)
			(stroke
				(width 0.1)
				(type default)
			)
			(layer "F.Fab")
		)
		(fp_line
			(start -0.12065 0.3048)
			(end -0.67945 0.3048)
			(stroke
				(width 0.1)
				(type default)
			)
			(layer "F.Fab")
		)
		(fp_line
			(start -0.67945 0.3048)
			(end -0.67945 -0.305054)
			(stroke
				(width 0.1)
				(type default)
			)
			(layer "F.Fab")
		)
		(pad "1" smd circle
			(at -0.40005 0 90)
			(size 0 0)
			(layers "F.Cu" "F.Mask" "F.Paste")
			(net "IRQ_TPM_SPI_R_N")
		)
		(pad "2" smd circle
			(at 0.40005 0 90)
			(size 0 0)
			(layers "F.Cu" "F.Mask" "F.Paste")
			(net "IRQ_TPM_SPI_R1_N")
		)
	)
	(footprint ""
		(layer "F.Cu")
		(at 52.011072 -401.989036 90)
		(property "Reference" "C7038"
			(at 0 0 90)
			(layer "F.SilkS")
			(hide yes)
			(effects
				(font
					(size 1.27 1.27)
				)
			)
		)
		(property "Value" ""
			(at 0 0 90)
			(layer "F.Fab")
			(effects
				(font
					(size 1.27 1.27)
				)
			)
		)
		(duplicate_pad_numbers_are_jumpers no)
		(fp_line
			(start 1.524 -0.762)
			(end 1.524 0.762)
			(stroke
				(width 0.1524)
				(type default)
			)
			(layer "F.SilkS")
		)
		(fp_line
			(start -1.524 -0.762)
			(end 1.524 -0.762)
			(stroke
				(width 0.1524)
				(type default)
			)
			(layer "F.SilkS")
		)
		(fp_line
			(start 1.524 0.762)
			(end -1.524 0.762)
			(stroke
				(width 0.1524)
				(type default)
			)
			(layer "F.SilkS")
		)
		(fp_line
			(start -1.524 0.762)
			(end -1.524 -0.762)
			(stroke
				(width 0.1524)
				(type default)
			)
			(layer "F.SilkS")
		)
		(fp_line
			(start 1.1049 -0.724916)
			(end -1.1049 -0.724916)
			(stroke
				(width 0.1)
				(type default)
			)
			(layer "F.Fab")
		)
		(fp_line
			(start -1.1049 -0.724916)
			(end -1.1049 0.724916)
			(stroke
				(width 0.1)
				(type default)
			)
			(layer "F.Fab")
		)
		(fp_line
			(start 1.1049 0.724916)
			(end 1.1049 -0.724916)
			(stroke
				(width 0.1)
				(type default)
			)
			(layer "F.Fab")
		)
		(fp_line
			(start -1.1049 0.724916)
			(end 1.1049 0.724916)
			(stroke
				(width 0.1)
				(type default)
			)
			(layer "F.Fab")
		)
		(pad "1" smd rect
			(at -0.889 0 270)
			(size 1.016 1.27)
			(layers "F.Cu" "F.Mask" "F.Paste")
			(net "P0V9_CPU1_RT_2D")
		)
		(pad "2" smd rect
			(at 0.889 0 270)
			(size 1.016 1.27)
			(layers "F.Cu" "F.Mask" "F.Paste")
			(net "GND")
		)
	)
)
